(kicad_pcb
	(version 20260206)
	(generator "pcbnew")
	(generator_version "10.0")
	(general
		(thickness 1.6)
		(legacy_teardrops no)
	)
	(paper "A4")
	(title_block
		(title "peb — Lightning_PEB_BRD.brd")
		(comment 1 "Lightning (Wiwynn / Facebook NVMe JBOF) / footprints 1411-1417 of 2563")
	)
	(layers
		(0 "F.Cu" signal "TOP")
		(4 "In1.Cu" signal "L2GND")
		(6 "In2.Cu" signal "L3")
		(8 "In3.Cu" signal "L4VCC")
		(10 "In4.Cu" signal "L5VCC")
		(12 "In5.Cu" signal "L6")
		(14 "In6.Cu" signal "L7GND")
		(2 "B.Cu" signal "BOTTOM")
		(9 "F.Adhes" user "F.Adhesive")
		(11 "B.Adhes" user "B.Adhesive")
		(13 "F.Paste" user "Package Geometry/Pastemask Top")
		(15 "B.Paste" user "Package Geometry/Pastemask Bottom")
		(5 "F.SilkS" user "Ref Des/Silkscreen Top")
		(7 "B.SilkS" user "Ref Des/Silkscreen Bottom")
		(1 "F.Mask" user "Board Geometry/Soldermask Top")
		(3 "B.Mask" user "Board Geometry/Soldermask Bottom")
		(17 "Dwgs.User" user "User.Drawings")
		(19 "Cmts.User" user "User.Comments")
		(21 "Eco1.User" user "User.Eco1")
		(23 "Eco2.User" user "User.Eco2")
		(25 "Edge.Cuts" user "Board Geometry/Outline")
		(27 "Margin" user)
		(31 "F.CrtYd" user "Package Geometry/Place Bound Top")
		(29 "B.CrtYd" user "Package Geometry/Place Bound Bottom")
		(35 "F.Fab" user "Ref Des/Assembly Top")
		(33 "B.Fab" user "Ref Des/Assembly Bottom")
	)
	(footprint ""
		(layer "F.Cu")
		(at 223.393 -23.241 180)
		(property "Reference" "R3724"
			(at 0 0 180)
			(layer "F.SilkS")
			(hide yes)
			(effects
				(font
					(size 1.27 1.27)
				)
			)
		)
		(property "Value" "4K7R2F-GP"
			(at 0.064008 -3.993896 180)
			(unlocked yes)
			(layer "F.Fab")
			(hide yes)
			(effects
				(font
					(size 1.016 1.016)
					(thickness 0.1524)
				)
			)
		)
		(property "Device Type" "R402H16"
			(at 0.064008 -5.517896 180)
			(unlocked yes)
			(layer "F.Fab")
			(hide yes)
			(effects
				(font
					(size 1.016 1.016)
					(thickness 0.1524)
				)
			)
		)
		(duplicate_pad_numbers_are_jumpers no)
		(fp_line
			(start 0.508 -0.9398)
			(end -0.508 -0.9398)
			(stroke
				(width 0.1524)
				(type default)
			)
			(layer "F.SilkS")
		)
		(fp_line
			(start -0.508 -0.9398)
			(end -0.508 0.9398)
			(stroke
				(width 0.1524)
				(type default)
			)
			(layer "F.SilkS")
		)
		(fp_rect
			(start -0.508 0.9398)
			(end 0.508 -0.9398)
			(stroke
				(width 0)
				(type default)
			)
			(fill no)
			(layer "F.CrtYd")
		)
		(fp_rect
			(start -0.508 0.9398)
			(end 0.508 -0.9398)
			(stroke
				(width 0)
				(type default)
			)
			(fill no)
			(layer "F.Fab")
		)
		(pad "1" smd custom
			(at 0 -0.4445 180)
			(size 0.1397 0.1397)
			(layers "F.Cu" "F.Mask" "F.Paste")
			(net "HOST7_RST_N_LS")
			(options
				(clearance outline)
				(anchor circle)
			)
			(primitives
				(gr_poly
					(pts
						(arc
							(start -0.1778 -0.2794)
							(mid -0.249642 -0.249642)
							(end -0.2794 -0.1778)
						)
						(arc
							(start -0.2794 0.1778)
							(mid -0.249642 0.249642)
							(end -0.1778 0.2794)
						)
						(arc
							(start 0.1778 0.2794)
							(mid 0.249642 0.249642)
							(end 0.2794 0.1778)
						)
						(arc
							(start 0.2794 -0.1778)
							(mid 0.249642 -0.249642)
							(end 0.1778 -0.2794)
						)
					)
					(width 0)
					(fill yes)
				)
			)
		)
		(pad "2" smd custom
			(at 0 0.4445 180)
			(size 0.1397 0.1397)
			(layers "F.Cu" "F.Mask" "F.Paste")
			(net "GND")
			(options
				(clearance outline)
				(anchor circle)
			)
			(primitives
				(gr_poly
					(pts
						(arc
							(start -0.1778 -0.2794)
							(mid -0.249642 -0.249642)
							(end -0.2794 -0.1778)
						)
						(arc
							(start -0.2794 0.1778)
							(mid -0.249642 0.249642)
							(end -0.1778 0.2794)
						)
						(arc
							(start 0.1778 0.2794)
							(mid 0.249642 0.249642)
							(end 0.2794 0.1778)
						)
						(arc
							(start 0.2794 -0.1778)
							(mid 0.249642 -0.249642)
							(end 0.1778 -0.2794)
						)
					)
					(width 0)
					(fill yes)
				)
			)
		)
	)
	(footprint ""
		(layer "F.Cu")
		(at 339.108034 -34.572194 180)
		(property "Reference" "R627"
			(at 0 0 180)
			(layer "F.SilkS")
			(hide yes)
			(effects
				(font
					(size 1.27 1.27)
				)
			)
		)
		(property "Value" "0R2J-2-GP"
			(at 0.064008 -3.993896 180)
			(unlocked yes)
			(layer "F.Fab")
			(hide yes)
			(effects
				(font
					(size 1.016 1.016)
					(thickness 0.1524)
				)
			)
		)
		(property "Device Type" "R402H16"
			(at 0.064008 -5.517896 180)
			(unlocked yes)
			(layer "F.Fab")
			(hide yes)
			(effects
				(font
					(size 1.016 1.016)
					(thickness 0.1524)
				)
			)
		)
		(duplicate_pad_numbers_are_jumpers no)
		(fp_line
			(start 0.508 -0.9398)
			(end -0.508 -0.9398)
			(stroke
				(width 0.1524)
				(type default)
			)
			(layer "F.SilkS")
		)
		(fp_line
			(start -0.508 -0.9398)
			(end -0.508 0.9398)
			(stroke
				(width 0.1524)
				(type default)
			)
			(layer "F.SilkS")
		)
		(fp_rect
			(start -0.508 0.9398)
			(end 0.508 -0.9398)
			(stroke
				(width 0)
				(type default)
			)
			(fill no)
			(layer "F.CrtYd")
		)
		(fp_rect
			(start -0.508 0.9398)
			(end 0.508 -0.9398)
			(stroke
				(width 0)
				(type default)
			)
			(fill no)
			(layer "F.Fab")
		)
		(pad "1" smd custom
			(at 0 -0.4445 180)
			(size 0.1397 0.1397)
			(layers "F.Cu" "F.Mask" "F.Paste")
			(net "UPLINK8_R")
			(options
				(clearance outline)
				(anchor circle)
			)
			(primitives
				(gr_poly
					(pts
						(arc
							(start -0.1778 -0.2794)
							(mid -0.249642 -0.249642)
							(end -0.2794 -0.1778)
						)
						(arc
							(start -0.2794 0.1778)
							(mid -0.249642 0.249642)
							(end -0.1778 0.2794)
						)
						(arc
							(start 0.1778 0.2794)
							(mid 0.249642 0.249642)
							(end 0.2794 0.1778)
						)
						(arc
							(start 0.2794 -0.1778)
							(mid 0.249642 -0.249642)
							(end 0.1778 -0.2794)
						)
					)
					(width 0)
					(fill yes)
				)
			)
		)
		(pad "2" smd custom
			(at 0 0.4445 180)
			(size 0.1397 0.1397)
			(layers "F.Cu" "F.Mask" "F.Paste")
			(net "UPLINK8")
			(options
				(clearance outline)
				(anchor circle)
			)
			(primitives
				(gr_poly
					(pts
						(arc
							(start -0.1778 -0.2794)
							(mid -0.249642 -0.249642)
							(end -0.2794 -0.1778)
						)
						(arc
							(start -0.2794 0.1778)
							(mid -0.249642 0.249642)
							(end -0.1778 0.2794)
						)
						(arc
							(start 0.1778 0.2794)
							(mid 0.249642 0.249642)
							(end 0.2794 0.1778)
						)
						(arc
							(start 0.2794 -0.1778)
							(mid 0.249642 -0.249642)
							(end 0.1778 -0.2794)
						)
					)
					(width 0)
					(fill yes)
				)
			)
		)
	)
	(footprint ""
		(layer "F.Cu")
		(at 75.180952 -149.52091 90)
		(property "Reference" "R199"
			(at 0 0 90)
			(layer "F.SilkS")
			(hide yes)
			(effects
				(font
					(size 1.27 1.27)
				)
			)
		)
		(property "Value" "8K2R2J-3-GP"
			(at 0.064008 -3.993896 90)
			(unlocked yes)
			(layer "F.Fab")
			(hide yes)
			(effects
				(font
					(size 1.016 1.016)
					(thickness 0.1524)
				)
			)
		)
		(property "Device Type" "R402H16"
			(at 0.064008 -5.517896 90)
			(unlocked yes)
			(layer "F.Fab")
			(hide yes)
			(effects
				(font
					(size 1.016 1.016)
					(thickness 0.1524)
				)
			)
		)
		(duplicate_pad_numbers_are_jumpers no)
		(fp_line
			(start 0.508 -0.9398)
			(end -0.508 -0.9398)
			(stroke
				(width 0.1524)
				(type default)
			)
			(layer "F.SilkS")
		)
		(fp_line
			(start -0.508 -0.9398)
			(end -0.508 0.9398)
			(stroke
				(width 0.1524)
				(type default)
			)
			(layer "F.SilkS")
		)
		(fp_rect
			(start -0.508 0.9398)
			(end 0.508 -0.9398)
			(stroke
				(width 0)
				(type default)
			)
			(fill no)
			(layer "F.CrtYd")
		)
		(fp_rect
			(start -0.508 0.9398)
			(end 0.508 -0.9398)
			(stroke
				(width 0)
				(type default)
			)
			(fill no)
			(layer "F.Fab")
		)
		(pad "1" smd custom
			(at 0 -0.4445 90)
			(size 0.1397 0.1397)
			(layers "F.Cu" "F.Mask" "F.Paste")
			(net "EEPROM_A2_R")
			(options
				(clearance outline)
				(anchor circle)
			)
			(primitives
				(gr_poly
					(pts
						(arc
							(start -0.1778 -0.2794)
							(mid -0.249642 -0.249642)
							(end -0.2794 -0.1778)
						)
						(arc
							(start -0.2794 0.1778)
							(mid -0.249642 0.249642)
							(end -0.1778 0.2794)
						)
						(arc
							(start 0.1778 0.2794)
							(mid 0.249642 0.249642)
							(end 0.2794 0.1778)
						)
						(arc
							(start 0.2794 -0.1778)
							(mid 0.249642 -0.249642)
							(end 0.1778 -0.2794)
						)
					)
					(width 0)
					(fill yes)
				)
			)
		)
		(pad "2" smd custom
			(at 0 0.4445 90)
			(size 0.1397 0.1397)
			(layers "F.Cu" "F.Mask" "F.Paste")
			(net "GND")
			(options
				(clearance outline)
				(anchor circle)
			)
			(primitives
				(gr_poly
					(pts
						(arc
							(start -0.1778 -0.2794)
							(mid -0.249642 -0.249642)
							(end -0.2794 -0.1778)
						)
						(arc
							(start -0.2794 0.1778)
							(mid -0.249642 0.249642)
							(end -0.1778 0.2794)
						)
						(arc
							(start 0.1778 0.2794)
							(mid 0.249642 0.249642)
							(end 0.2794 0.1778)
						)
						(arc
							(start 0.2794 -0.1778)
							(mid 0.249642 -0.249642)
							(end 0.1778 -0.2794)
						)
					)
					(width 0)
					(fill yes)
				)
			)
		)
	)
	(footprint ""
		(layer "F.Cu")
		(at 238.5314 -17.1196 90)
		(property "Reference" "Q22"
			(at 0 0 90)
			(layer "F.SilkS")
			(hide yes)
			(effects
				(font
					(size 1.27 1.27)
				)
			)
		)
		(property "Value" "2N7002K-1-GP"
			(at 0.127 -8.9662 90)
			(unlocked yes)
			(layer "F.Fab")
			(hide yes)
			(effects
				(font
					(size 1.016 1.016)
					(thickness 0.1524)
				)
			)
		)
		(property "Device Type" "SOT23DGS2D4H44"
			(at 0.127 -10.4902 90)
			(unlocked yes)
			(layer "F.Fab")
			(hide yes)
			(effects
				(font
					(size 1.016 1.016)
					(thickness 0.1524)
				)
			)
		)
		(duplicate_pad_numbers_are_jumpers no)
		(fp_line
			(start 1.651 -1.778)
			(end -1.651 -1.778)
			(stroke
				(width 0.1524)
				(type default)
			)
			(layer "F.SilkS")
		)
		(fp_line
			(start -1.651 -1.778)
			(end -1.651 1.778)
			(stroke
				(width 0.1524)
				(type default)
			)
			(layer "F.SilkS")
		)
		(fp_line
			(start 1.651 1.778)
			(end 1.651 -1.778)
			(stroke
				(width 0.1524)
				(type default)
			)
			(layer "F.SilkS")
		)
		(fp_line
			(start -1.651 1.778)
			(end 1.651 1.778)
			(stroke
				(width 0.1524)
				(type default)
			)
			(layer "F.SilkS")
		)
		(fp_poly
			(pts
				(xy -1.778 1.8796) (xy -1.778 -1.8796) (xy 1.778 -1.8796) (xy 1.778 1.8796)
			)
			(stroke
				(width 0)
				(type default)
			)
			(fill no)
			(layer "F.CrtYd")
		)
		(fp_poly
			(pts
				(xy -1.778 1.8796) (xy -1.778 -1.8796) (xy 1.778 -1.8796) (xy 1.778 1.8796)
			)
			(stroke
				(width 0)
				(type default)
			)
			(fill no)
			(layer "F.Fab")
		)
		(pad "D" smd custom
			(at 0 -0.9525 90)
			(size 0.1905 0.1905)
			(layers "F.Cu" "F.Mask" "F.Paste")
			(net "Q22_D")
			(options
				(clearance outline)
				(anchor circle)
			)
			(primitives
				(gr_poly
					(pts
						(arc
							(start -0.1778 0.5715)
							(mid -0.321484 0.511984)
							(end -0.381 0.3683)
						)
						(arc
							(start -0.381 -0.3683)
							(mid -0.321484 -0.511984)
							(end -0.1778 -0.5715)
						)
						(arc
							(start 0.1778 -0.5715)
							(mid 0.321484 -0.511984)
							(end 0.381 -0.3683)
						)
						(arc
							(start 0.381 0.3683)
							(mid 0.321484 0.511984)
							(end 0.1778 0.5715)
						)
					)
					(width 0)
					(fill yes)
				)
			)
		)
		(pad "G" smd custom
			(at -0.98425 0.9525 90)
			(size 0.1905 0.1905)
			(layers "F.Cu" "F.Mask" "F.Paste")
			(net "Q22_G")
			(options
				(clearance outline)
				(anchor circle)
			)
			(primitives
				(gr_poly
					(pts
						(arc
							(start -0.1778 0.5715)
							(mid -0.321484 0.511984)
							(end -0.381 0.3683)
						)
						(arc
							(start -0.381 -0.3683)
							(mid -0.321484 -0.511984)
							(end -0.1778 -0.5715)
						)
						(arc
							(start 0.1778 -0.5715)
							(mid 0.321484 -0.511984)
							(end 0.381 -0.3683)
						)
						(arc
							(start 0.381 0.3683)
							(mid 0.321484 0.511984)
							(end 0.1778 0.5715)
						)
					)
					(width 0)
					(fill yes)
				)
			)
		)
		(pad "S" smd custom
			(at 0.98425 0.9525 90)
			(size 0.1905 0.1905)
			(layers "F.Cu" "F.Mask" "F.Paste")
			(net "GND")
			(options
				(clearance outline)
				(anchor circle)
			)
			(primitives
				(gr_poly
					(pts
						(arc
							(start -0.1778 0.5715)
							(mid -0.321484 0.511984)
							(end -0.381 0.3683)
						)
						(arc
							(start -0.381 -0.3683)
							(mid -0.321484 -0.511984)
							(end -0.1778 -0.5715)
						)
						(arc
							(start 0.1778 -0.5715)
							(mid 0.321484 -0.511984)
							(end 0.381 -0.3683)
						)
						(arc
							(start 0.381 0.3683)
							(mid 0.321484 0.511984)
							(end 0.1778 0.5715)
						)
					)
					(width 0)
					(fill yes)
				)
			)
		)
	)
	(footprint ""
		(layer "F.Cu")
		(at 160.528 -83.5914 90)
		(property "Reference" "TP78"
			(at 0 0 90)
			(layer "F.SilkS")
			(hide yes)
			(effects
				(font
					(size 1.27 1.27)
				)
			)
		)
		(property "Value" "TPAD28-2-GP"
			(at -0.0127 -1.6637 90)
			(unlocked yes)
			(layer "F.Fab")
			(hide yes)
			(effects
				(font
					(size 1.016 1.016)
					(thickness 0.1524)
				)
			)
		)
		(property "Device Type" "TPAD28"
			(at -0.0127 -3.1877 90)
			(unlocked yes)
			(layer "F.Fab")
			(hide yes)
			(effects
				(font
					(size 1.016 1.016)
					(thickness 0.1524)
				)
			)
		)
		(duplicate_pad_numbers_are_jumpers no)
		(fp_poly
			(pts
				(arc
					(start 0 0.3556)
					(mid 0 -0.3556)
					(end 0 0.3556)
				)
			)
			(stroke
				(width 0)
				(type default)
			)
			(fill no)
			(layer "F.CrtYd")
		)
		(fp_poly
			(pts
				(arc
					(start 0 0.6096)
					(mid 0 -0.6096)
					(end 0 0.6096)
				)
			)
			(stroke
				(width 0)
				(type default)
			)
			(fill no)
			(layer "F.Fab")
		)
		(pad "1" smd circle
			(at 0 0 90)
			(size 0.7112 0.7112)
			(layers "F.Cu" "F.Mask" "F.Paste")
			(net "PCIE_CLKGEN2_OE0")
		)
	)
	(footprint ""
		(layer "F.Cu")
		(at 71.755 -125.349 180)
		(property "Reference" "R426"
			(at 0 0 180)
			(layer "F.SilkS")
			(hide yes)
			(effects
				(font
					(size 1.27 1.27)
				)
			)
		)
		(property "Value" "10KR2F-2-GP"
			(at 0.064008 -3.993896 180)
			(unlocked yes)
			(layer "F.Fab")
			(hide yes)
			(effects
				(font
					(size 1.016 1.016)
					(thickness 0.1524)
				)
			)
		)
		(property "Device Type" "R402H16"
			(at 0.064008 -5.517896 180)
			(unlocked yes)
			(layer "F.Fab")
			(hide yes)
			(effects
				(font
					(size 1.016 1.016)
					(thickness 0.1524)
				)
			)
		)
		(duplicate_pad_numbers_are_jumpers no)
		(fp_line
			(start 0.508 -0.9398)
			(end -0.508 -0.9398)
			(stroke
				(width 0.1524)
				(type default)
			)
			(layer "F.SilkS")
		)
		(fp_line
			(start -0.508 -0.9398)
			(end -0.508 0.9398)
			(stroke
				(width 0.1524)
				(type default)
			)
			(layer "F.SilkS")
		)
		(fp_rect
			(start -0.508 0.9398)
			(end 0.508 -0.9398)
			(stroke
				(width 0)
				(type default)
			)
			(fill no)
			(layer "F.CrtYd")
		)
		(fp_rect
			(start -0.508 0.9398)
			(end 0.508 -0.9398)
			(stroke
				(width 0)
				(type default)
			)
			(fill no)
			(layer "F.Fab")
		)
		(pad "1" smd custom
			(at 0 -0.4445 180)
			(size 0.1397 0.1397)
			(layers "F.Cu" "F.Mask" "F.Paste")
			(net "P3V3_STBY")
			(options
				(clearance outline)
				(anchor circle)
			)
			(primitives
				(gr_poly
					(pts
						(arc
							(start -0.1778 -0.2794)
							(mid -0.249642 -0.249642)
							(end -0.2794 -0.1778)
						)
						(arc
							(start -0.2794 0.1778)
							(mid -0.249642 0.249642)
							(end -0.1778 0.2794)
						)
						(arc
							(start 0.1778 0.2794)
							(mid 0.249642 0.249642)
							(end 0.2794 0.1778)
						)
						(arc
							(start 0.2794 -0.1778)
							(mid 0.249642 -0.249642)
							(end 0.1778 -0.2794)
						)
					)
					(width 0)
					(fill yes)
				)
			)
		)
		(pad "2" smd custom
			(at 0 0.4445 180)
			(size 0.1397 0.1397)
			(layers "F.Cu" "F.Mask" "F.Paste")
			(net "MBP_UART_TX")
			(options
				(clearance outline)
				(anchor circle)
			)
			(primitives
				(gr_poly
					(pts
						(arc
							(start -0.1778 -0.2794)
							(mid -0.249642 -0.249642)
							(end -0.2794 -0.1778)
						)
						(arc
							(start -0.2794 0.1778)
							(mid -0.249642 0.249642)
							(end -0.1778 0.2794)
						)
						(arc
							(start 0.1778 0.2794)
							(mid 0.249642 0.249642)
							(end 0.2794 0.1778)
						)
						(arc
							(start 0.2794 -0.1778)
							(mid 0.249642 -0.249642)
							(end 0.1778 -0.2794)
						)
					)
					(width 0)
					(fill yes)
				)
			)
		)
	)
	(footprint ""
		(layer "F.Cu")
		(at 151.19223 -212.420454 180)
		(property "Reference" "C252"
			(at 0 0 180)
			(layer "F.SilkS")
			(hide yes)
			(effects
				(font
					(size 1.27 1.27)
				)
			)
		)
		(property "Value" "SCD22U10V2KX-1GP"
			(at 1.1811 -2.7051 180)
			(unlocked yes)
			(layer "F.Fab")
			(hide yes)
			(effects
				(font
					(size 1.016 1.016)
					(thickness 0.1524)
				)
			)
		)
		(property "Device Type" "C402H22"
			(at 1.1811 -4.2291 180)
			(unlocked yes)
			(layer "F.Fab")
			(hide yes)
			(effects
				(font
					(size 1.016 1.016)
					(thickness 0.1524)
				)
			)
		)
		(duplicate_pad_numbers_are_jumpers no)
		(fp_rect
			(start -0.4318 0.9525)
			(end 0.4318 -0.9525)
			(stroke
				(width 0)
				(type default)
			)
			(fill no)
			(layer "F.CrtYd")
		)
		(fp_rect
			(start -0.4318 0.9525)
			(end 0.4318 -0.9525)
			(stroke
				(width 0)
				(type default)
			)
			(fill no)
			(layer "F.Fab")
		)
		(pad "1" smd custom
			(at 0 -0.4445 180)
			(size 0.1524 0.1524)
			(layers "F.Cu" "F.Mask" "F.Paste")
			(net "PCIE_TX_CAP_P55")
			(options
				(clearance outline)
				(anchor circle)
			)
			(primitives
				(gr_poly
					(pts
						(arc
							(start 0.3048 -0.2032)
							(mid 0.275042 -0.275042)
							(end 0.2032 -0.3048)
						)
						(arc
							(start -0.2032 -0.3048)
							(mid -0.275042 -0.275042)
							(end -0.3048 -0.2032)
						)
						(arc
							(start -0.3048 0.2032)
							(mid -0.275042 0.275042)
							(end -0.2032 0.3048)
						)
						(arc
							(start 0.2032 0.3048)
							(mid 0.275042 0.275042)
							(end 0.3048 0.2032)
						)
					)
					(width 0)
					(fill yes)
				)
			)
		)
		(pad "2" smd custom
			(at 0 0.4445 180)
			(size 0.1524 0.1524)
			(layers "F.Cu" "F.Mask" "F.Paste")
			(net "PCIE_TX_P55")
			(options
				(clearance outline)
				(anchor circle)
			)
			(primitives
				(gr_poly
					(pts
						(arc
							(start 0.3048 -0.2032)
							(mid 0.275042 -0.275042)
							(end 0.2032 -0.3048)
						)
						(arc
							(start -0.2032 -0.3048)
							(mid -0.275042 -0.275042)
							(end -0.3048 -0.2032)
						)
						(arc
							(start -0.3048 0.2032)
							(mid -0.275042 0.275042)
							(end -0.2032 0.3048)
						)
						(arc
							(start 0.2032 0.3048)
							(mid 0.275042 0.275042)
							(end 0.3048 0.2032)
						)
					)
					(width 0)
					(fill yes)
				)
			)
		)
	)
)
